(kicad_pcb
	(version 20260206)
	(generator "pcbnew")
	(generator_version "10.0")
	(general
		(thickness 1.6)
		(legacy_teardrops no)
	)
	(paper "A4")
	(title_block
		(title "v1-pdb — T6M_PDB_D_0927_0900.brd")
		(comment 1 "Open CloudServer (Microsoft) / footprints 27-34 of 321")
	)
	(layers
		(0 "F.Cu" signal "TOP")
		(4 "In1.Cu" signal "GND")
		(6 "In2.Cu" signal "IN1")
		(8 "In3.Cu" signal "VCC")
		(10 "In4.Cu" signal "VCC1")
		(12 "In5.Cu" signal "IN2")
		(14 "In6.Cu" signal "GND1")
		(2 "B.Cu" signal "BOTTOM")
		(9 "F.Adhes" user "F.Adhesive")
		(11 "B.Adhes" user "B.Adhesive")
		(13 "F.Paste" user "Package Geometry/Pastemask Top")
		(15 "B.Paste" user "Package Geometry/Pastemask Bottom")
		(5 "F.SilkS" user "Ref Des/Silkscreen Top")
		(7 "B.SilkS" user "Ref Des/Silkscreen Bottom")
		(1 "F.Mask" user "Board Geometry/Soldermask Top")
		(3 "B.Mask" user "Board Geometry/Soldermask Bottom")
		(17 "Dwgs.User" user "User.Drawings")
		(19 "Cmts.User" user "User.Comments")
		(21 "Eco1.User" user "User.Eco1")
		(23 "Eco2.User" user "User.Eco2")
		(25 "Edge.Cuts" user "Board Geometry/Outline")
		(27 "Margin" user)
		(31 "F.CrtYd" user "Package Geometry/Place Bound Top")
		(29 "B.CrtYd" user "Package Geometry/Place Bound Bottom")
		(35 "F.Fab" user "Ref Des/Assembly Top")
		(33 "B.Fab" user "Ref Des/Assembly Bottom")
	)
	(footprint ""
		(layer "F.Cu")
		(at 73.57745 -397.262604 90)
		(property "Reference" "C69"
			(at -1.662176 -4.920742 90)
			(unlocked yes)
			(layer "F.SilkS")
			(effects
				(font
					(size 0.7874 0.5842)
					(thickness 0.1524)
				)
				(justify left)
			)
		)
		(property "Value" ""
			(at 0 0 90)
			(layer "F.Fab")
			(effects
				(font
					(size 1.27 1.27)
				)
			)
		)
		(duplicate_pad_numbers_are_jumpers no)
		(fp_line
			(start 0.7874 -0.4064)
			(end 0.7874 0.4064)
			(stroke
				(width 0.1524)
				(type default)
			)
			(layer "F.SilkS")
		)
		(fp_line
			(start -0.7874 -0.4064)
			(end 0.7874 -0.4064)
			(stroke
				(width 0.1524)
				(type default)
			)
			(layer "F.SilkS")
		)
		(fp_line
			(start 0 0.381)
			(end 0 -0.381)
			(stroke
				(width 0.1524)
				(type default)
			)
			(layer "F.SilkS")
		)
		(fp_line
			(start 0.7874 0.4064)
			(end -0.7874 0.4064)
			(stroke
				(width 0.1524)
				(type default)
			)
			(layer "F.SilkS")
		)
		(fp_line
			(start -0.7874 0.4064)
			(end -0.7874 -0.4064)
			(stroke
				(width 0.1524)
				(type default)
			)
			(layer "F.SilkS")
		)
		(fp_poly
			(pts
				(xy -0.5334 0.254) (xy -0.635 0.254) (xy -0.635 0.2286) (xy -0.635 -0.254) (xy -0.5334 -0.254) (xy -0.5334 -0.2794)
				(xy 0.5334 -0.2794) (xy 0.5334 -0.254) (xy 0.635 -0.254) (xy 0.635 0.254) (xy 0.5334 0.254) (xy 0.5334 0.2794)
				(xy -0.508 0.2794) (xy -0.5334 0.2794)
			)
			(stroke
				(width 0)
				(type default)
			)
			(fill no)
			(layer "F.CrtYd")
		)
		(pad "1" smd rect
			(at 0.40005 0 90)
			(size 0.4572 0.508)
			(layers "F.Cu" "F.Mask" "F.Paste")
			(net "P12V")
		)
		(pad "2" smd rect
			(at -0.40005 0 90)
			(size 0.4572 0.508)
			(layers "F.Cu" "F.Mask" "F.Paste")
			(net "GND")
		)
	)
	(footprint ""
		(layer "F.Cu")
		(at 46.425612 -253.125732 180)
		(property "Reference" "R99"
			(at 2.224278 1.16205 0)
			(unlocked yes)
			(layer "F.SilkS")
			(effects
				(font
					(size 0.7874 0.5842)
					(thickness 0.1524)
				)
				(justify left)
			)
		)
		(property "Value" ""
			(at 0 0 180)
			(layer "F.Fab")
			(effects
				(font
					(size 1.27 1.27)
				)
			)
		)
		(duplicate_pad_numbers_are_jumpers no)
		(fp_line
			(start 0.7874 0.4064)
			(end -0.7874 0.4064)
			(stroke
				(width 0.1524)
				(type default)
			)
			(layer "F.SilkS")
		)
		(fp_line
			(start 0.7874 -0.4064)
			(end 0.7874 0.4064)
			(stroke
				(width 0.1524)
				(type default)
			)
			(layer "F.SilkS")
		)
		(fp_line
			(start -0.7874 0.4064)
			(end -0.7874 -0.4064)
			(stroke
				(width 0.1524)
				(type default)
			)
			(layer "F.SilkS")
		)
		(fp_line
			(start -0.7874 -0.4064)
			(end 0.7874 -0.4064)
			(stroke
				(width 0.1524)
				(type default)
			)
			(layer "F.SilkS")
		)
		(fp_poly
			(pts
				(xy -0.508 0.2794) (xy -0.508 0.2286) (xy -0.635 0.2286) (xy -0.635 -0.254) (xy -0.5334 -0.254)
				(xy -0.5334 -0.2794) (xy 0.5334 -0.2794) (xy 0.5334 -0.254) (xy 0.635 -0.254) (xy 0.635 0.254) (xy 0.5334 0.254)
				(xy 0.5334 0.2794)
			)
			(stroke
				(width 0)
				(type default)
			)
			(fill no)
			(layer "F.CrtYd")
		)
		(pad "1" smd rect
			(at 0.40005 0 180)
			(size 0.4572 0.508)
			(layers "F.Cu" "F.Mask" "F.Paste")
			(net "PSU6_REMOTE_R_N")
		)
		(pad "2" smd rect
			(at -0.40005 0 180)
			(size 0.4572 0.508)
			(layers "F.Cu" "F.Mask" "F.Paste")
			(net "GND")
		)
	)
	(footprint ""
		(layer "F.Cu")
		(at 40.056562 -281.140662 180)
		(property "Reference" "R25"
			(at -1.619504 -0.058166 0)
			(unlocked yes)
			(layer "F.SilkS")
			(effects
				(font
					(size 0.7874 0.5842)
					(thickness 0.1524)
				)
				(justify left)
			)
		)
		(property "Value" ""
			(at 0 0 180)
			(layer "F.Fab")
			(effects
				(font
					(size 1.27 1.27)
				)
			)
		)
		(duplicate_pad_numbers_are_jumpers no)
		(fp_line
			(start 0.7874 0.4064)
			(end -0.7874 0.4064)
			(stroke
				(width 0.1524)
				(type default)
			)
			(layer "F.SilkS")
		)
		(fp_line
			(start 0.7874 -0.4064)
			(end 0.7874 0.4064)
			(stroke
				(width 0.1524)
				(type default)
			)
			(layer "F.SilkS")
		)
		(fp_line
			(start -0.7874 0.4064)
			(end -0.7874 -0.4064)
			(stroke
				(width 0.1524)
				(type default)
			)
			(layer "F.SilkS")
		)
		(fp_line
			(start -0.7874 -0.4064)
			(end 0.7874 -0.4064)
			(stroke
				(width 0.1524)
				(type default)
			)
			(layer "F.SilkS")
		)
		(fp_poly
			(pts
				(xy -0.508 0.2794) (xy -0.508 0.2286) (xy -0.635 0.2286) (xy -0.635 -0.254) (xy -0.5334 -0.254)
				(xy -0.5334 -0.2794) (xy 0.5334 -0.2794) (xy 0.5334 -0.254) (xy 0.635 -0.254) (xy 0.635 0.254) (xy 0.5334 0.254)
				(xy 0.5334 0.2794)
			)
			(stroke
				(width 0)
				(type default)
			)
			(fill no)
			(layer "F.CrtYd")
		)
		(pad "1" smd rect
			(at 0.40005 0 180)
			(size 0.4572 0.508)
			(layers "F.Cu" "F.Mask" "F.Paste")
			(net "PSU4_RETURN")
		)
		(pad "2" smd rect
			(at -0.40005 0 180)
			(size 0.4572 0.508)
			(layers "F.Cu" "F.Mask" "F.Paste")
			(net "GND")
		)
	)
	(footprint ""
		(layer "F.Cu")
		(at 91.399868 -64.46012)
		(property "Reference" "H16"
			(at -5.1308 -5.23113 0)
			(unlocked yes)
			(layer "F.SilkS")
			(effects
				(font
					(size 0.7874 0.5842)
					(thickness 0.1524)
				)
				(justify left)
			)
		)
		(property "Value" ""
			(at 0 0 0)
			(layer "F.Fab")
			(effects
				(font
					(size 1.27 1.27)
				)
			)
		)
		(duplicate_pad_numbers_are_jumpers no)
		(fp_circle
			(center 0 0)
			(end 4.826 0)
			(stroke
				(width 0.1524)
				(type default)
			)
			(fill no)
			(layer "F.SilkS")
		)
		(fp_circle
			(center 0 0)
			(end 4.826 0)
			(stroke
				(width 0.1524)
				(type default)
			)
			(fill no)
			(layer "B.SilkS")
		)
		(fp_poly
			(pts
				(arc
					(start 0 4.0132)
					(mid 0 -4.0132)
					(end 0 4.0132)
				)
			)
			(stroke
				(width 0)
				(type default)
			)
			(fill no)
			(layer "F.CrtYd")
		)
		(pad "" np_thru_hole circle
			(at 0 0)
			(size 8.001 8.001)
			(drill 8.001)
			(layers "*.Cu" "*.Mask")
			(clearance 0.381)
			(thermal_gap 0.381)
		)
		(zone
			(layers "F.Cu" "B.Cu" "In1.Cu" "In2.Cu" "In3.Cu" "In4.Cu" "In5.Cu" "In6.Cu")
			(hatch none 0.5)
			(connect_pads
				(clearance 0)
			)
			(min_thickness 0.25)
			(keepout
				(tracks not_allowed)
				(vias allowed)
				(pads allowed)
				(copperpour not_allowed)
				(footprints allowed)
			)
			(placement
				(enabled no)
				(sheetname "")
			)
			(fill
				(thermal_gap 0.5)
				(thermal_bridge_width 0.5)
				(island_removal_mode 0)
			)
			(polygon
				(pts
					(arc
						(start 91.399868 -59.93892)
						(mid 91.399868 -68.98132)
						(end 91.399868 -59.93892)
					)
				)
			)
		)
	)
	(footprint ""
		(layer "F.Cu")
		(at 26.102056 -271.14881)
		(property "Reference" "R77"
			(at -4.037838 -0.005334 0)
			(unlocked yes)
			(layer "F.SilkS")
			(effects
				(font
					(size 0.7874 0.5842)
					(thickness 0.1524)
				)
				(justify left)
			)
		)
		(property "Value" ""
			(at 0 0 0)
			(layer "F.Fab")
			(effects
				(font
					(size 1.27 1.27)
				)
			)
		)
		(duplicate_pad_numbers_are_jumpers no)
		(fp_line
			(start -0.7874 -0.4064)
			(end 0.7874 -0.4064)
			(stroke
				(width 0.1524)
				(type default)
			)
			(layer "F.SilkS")
		)
		(fp_line
			(start -0.7874 0.4064)
			(end -0.7874 -0.4064)
			(stroke
				(width 0.1524)
				(type default)
			)
			(layer "F.SilkS")
		)
		(fp_line
			(start 0.7874 -0.4064)
			(end 0.7874 0.4064)
			(stroke
				(width 0.1524)
				(type default)
			)
			(layer "F.SilkS")
		)
		(fp_line
			(start 0.7874 0.4064)
			(end -0.7874 0.4064)
			(stroke
				(width 0.1524)
				(type default)
			)
			(layer "F.SilkS")
		)
		(fp_poly
			(pts
				(xy -0.508 0.2794) (xy -0.508 0.2286) (xy -0.635 0.2286) (xy -0.635 -0.254) (xy -0.5334 -0.254)
				(xy -0.5334 -0.2794) (xy 0.5334 -0.2794) (xy 0.5334 -0.254) (xy 0.635 -0.254) (xy 0.635 0.254) (xy 0.5334 0.254)
				(xy 0.5334 0.2794)
			)
			(stroke
				(width 0)
				(type default)
			)
			(fill no)
			(layer "F.CrtYd")
		)
		(pad "1" smd rect
			(at 0.40005 0)
			(size 0.4572 0.508)
			(layers "F.Cu" "F.Mask" "F.Paste")
			(net "PSU4_RESET")
		)
		(pad "2" smd rect
			(at -0.40005 0)
			(size 0.4572 0.508)
			(layers "F.Cu" "F.Mask" "F.Paste")
			(net "GND")
		)
	)
	(footprint ""
		(layer "F.Cu")
		(at 50.554382 -418.636958 180)
		(property "Reference" "CE19"
			(at 6.458458 3.641344 0)
			(unlocked yes)
			(layer "F.SilkS")
			(effects
				(font
					(size 0.7874 0.5842)
					(thickness 0.1524)
				)
				(justify left)
			)
		)
		(property "Value" ""
			(at 0 0 180)
			(layer "F.Fab")
			(effects
				(font
					(size 1.27 1.27)
				)
			)
		)
		(duplicate_pad_numbers_are_jumpers no)
		(fp_line
			(start 0 -4.2672)
			(end 0 4.2672)
			(stroke
				(width 0.1524)
				(type default)
			)
			(layer "F.SilkS")
		)
		(fp_circle
			(center 0 0)
			(end -4.2672 0)
			(stroke
				(width 0.1524)
				(type default)
			)
			(fill no)
			(layer "F.SilkS")
		)
		(fp_poly
			(pts
				(arc
					(start 0 -4.2672)
					(mid 4.2672 0)
					(end 0 4.2672)
				)
			)
			(stroke
				(width 0)
				(type default)
			)
			(fill yes)
			(layer "F.SilkS")
		)
		(fp_poly
			(pts
				(xy -2.5146 -0.762) (xy -0.9906 -0.762) (xy -0.9906 0.762) (xy -2.5146 0.762)
			)
			(stroke
				(width 0)
				(type default)
			)
			(fill no)
			(layer "B.CrtYd")
		)
		(fp_poly
			(pts
				(arc
					(start 1.7526 0.762)
					(mid 2.291415 -0.538815)
					(end 0.9906 0)
				)
				(arc
					(start 0.9906 0.0254)
					(mid 1.206345 0.546255)
					(end 1.7272 0.762)
				)
			)
			(stroke
				(width 0)
				(type default)
			)
			(fill no)
			(layer "B.CrtYd")
		)
		(fp_poly
			(pts
				(arc
					(start -4.2672 0)
					(mid 4.2672 0)
					(end -4.2672 0)
				)
			)
			(stroke
				(width 0)
				(type default)
			)
			(fill no)
			(layer "F.CrtYd")
		)
		(fp_circle
			(center 0 0)
			(end -4.2672 0)
			(stroke
				(width 0.1)
				(type default)
			)
			(fill no)
			(layer "F.Fab")
		)
		(fp_text user "+"
			(at -5.103114 1.718056 180)
			(unlocked yes)
			(layer "F.SilkS")
			(effects
				(font
					(size 0.7874 0.5842)
					(thickness 0.1524)
				)
				(justify left)
			)
		)
		(fp_text user "+"
			(at -5.6642 -0.34925 180)
			(unlocked yes)
			(layer "F.Fab")
			(effects
				(font
					(size 1.905 1.4224)
					(thickness 0.000001)
				)
				(justify left)
			)
		)
		(pad "1" thru_hole rect
			(at -1.75006 0 180)
			(size 1.397 1.397)
			(drill 0.9144)
			(layers "*.Cu" "*.Mask")
			(remove_unused_layers no)
			(net "P12V")
			(clearance 0.0127)
			(thermal_gap 0.0127)
			(padstack
				(mode front_inner_back)
				(layer "Inner"
					(shape circle)
					(size 1.397 1.397)
					(clearance 0.0127)
				)
				(layer "B.Cu"
					(shape rect)
					(size 1.397 1.397)
					(clearance 0.0127)
				)
			)
		)
		(pad "2" thru_hole circle
			(at 1.75006 0 180)
			(size 1.397 1.397)
			(drill 0.9144)
			(layers "*.Cu" "*.Mask")
			(remove_unused_layers no)
			(net "GND")
			(clearance 0.0127)
			(thermal_gap 0.0127)
		)
	)
	(footprint ""
		(layer "F.Cu")
		(at 26.226008 -447.250058)
		(property "Reference" "R61"
			(at -3.597402 -0.121666 0)
			(unlocked yes)
			(layer "F.SilkS")
			(effects
				(font
					(size 0.7874 0.5842)
					(thickness 0.1524)
				)
				(justify left)
			)
		)
		(property "Value" ""
			(at 0 0 0)
			(layer "F.Fab")
			(effects
				(font
					(size 1.27 1.27)
				)
			)
		)
		(duplicate_pad_numbers_are_jumpers no)
		(fp_line
			(start -0.7874 -0.4064)
			(end 0.7874 -0.4064)
			(stroke
				(width 0.1524)
				(type default)
			)
			(layer "F.SilkS")
		)
		(fp_line
			(start -0.7874 0.4064)
			(end -0.7874 -0.4064)
			(stroke
				(width 0.1524)
				(type default)
			)
			(layer "F.SilkS")
		)
		(fp_line
			(start 0.7874 -0.4064)
			(end 0.7874 0.4064)
			(stroke
				(width 0.1524)
				(type default)
			)
			(layer "F.SilkS")
		)
		(fp_line
			(start 0.7874 0.4064)
			(end -0.7874 0.4064)
			(stroke
				(width 0.1524)
				(type default)
			)
			(layer "F.SilkS")
		)
		(fp_poly
			(pts
				(xy -0.508 0.2794) (xy -0.508 0.2286) (xy -0.635 0.2286) (xy -0.635 -0.254) (xy -0.5334 -0.254)
				(xy -0.5334 -0.2794) (xy 0.5334 -0.2794) (xy 0.5334 -0.254) (xy 0.635 -0.254) (xy 0.635 0.254) (xy 0.5334 0.254)
				(xy 0.5334 0.2794)
			)
			(stroke
				(width 0)
				(type default)
			)
			(fill no)
			(layer "F.CrtYd")
		)
		(pad "1" smd rect
			(at 0.40005 0)
			(size 0.4572 0.508)
			(layers "F.Cu" "F.Mask" "F.Paste")
			(net "PSU6_RESET")
		)
		(pad "2" smd rect
			(at -0.40005 0)
			(size 0.4572 0.508)
			(layers "F.Cu" "F.Mask" "F.Paste")
			(net "GND")
		)
	)
	(footprint ""
		(layer "F.Cu")
		(at 77.999844 -430.150016)
		(property "Reference" "H3"
			(at -6.4516 -7.127748 0)
			(unlocked yes)
			(layer "F.SilkS")
			(effects
				(font
					(size 0.7874 0.5842)
					(thickness 0.1524)
				)
				(justify left)
			)
		)
		(property "Value" ""
			(at 0 0 0)
			(layer "F.Fab")
			(effects
				(font
					(size 1.27 1.27)
				)
			)
		)
		(duplicate_pad_numbers_are_jumpers no)
		(fp_circle
			(center 0 0)
			(end 7.999984 0)
			(stroke
				(width 0.1524)
				(type default)
			)
			(fill no)
			(layer "F.SilkS")
		)
		(fp_arc
			(start -4.620006 -13.962126)
			(mid 8.612183 -11.921174)
			(end 14.7066 0)
			(stroke
				(width 0.1524)
				(type default)
			)
			(layer "B.SilkS")
		)
		(fp_arc
			(start 14.7066 0)
			(mid -8.042606 12.311424)
			(end -5.908802 -13.467334)
			(stroke
				(width 0.1524)
				(type default)
			)
			(layer "B.SilkS")
		)
		(fp_poly
			(pts
				(arc
					(start 5.0038 0)
					(mid -5.0038 0)
					(end 5.0038 0)
				)
			)
			(stroke
				(width 0)
				(type default)
			)
			(fill no)
			(layer "F.CrtYd")
		)
		(pad "" np_thru_hole circle
			(at 0 0)
			(size 4.0132 4.0132)
			(drill 4.0132)
			(layers "*.Cu" "*.Mask")
			(clearance 0.381)
			(thermal_gap 0.381)
		)
		(pad "2" thru_hole circle
			(at 0 -3.50012)
			(size 0.762 0.762)
			(drill 0.5588)
			(layers "*.Cu" "*.Mask")
			(remove_unused_layers no)
			(net "GND")
			(clearance 0.1524)
			(thermal_gap 0.1524)
		)
		(pad "3" thru_hole circle
			(at -2.500122 -2.500122)
			(size 0.762 0.762)
			(drill 0.5588)
			(layers "*.Cu" "*.Mask")
			(remove_unused_layers no)
			(net "GND")
			(clearance 0.1524)
			(thermal_gap 0.1524)
		)
		(pad "4" thru_hole circle
			(at -3.50012 0)
			(size 0.762 0.762)
			(drill 0.5588)
			(layers "*.Cu" "*.Mask")
			(remove_unused_layers no)
			(net "GND")
			(clearance 0.1524)
			(thermal_gap 0.1524)
		)
		(pad "5" thru_hole circle
			(at -2.500122 2.500122)
			(size 0.762 0.762)
			(drill 0.5588)
			(layers "*.Cu" "*.Mask")
			(remove_unused_layers no)
			(net "GND")
			(clearance 0.1524)
			(thermal_gap 0.1524)
		)
		(pad "6" thru_hole circle
			(at 0 3.50012)
			(size 0.762 0.762)
			(drill 0.5588)
			(layers "*.Cu" "*.Mask")
			(remove_unused_layers no)
			(net "GND")
			(clearance 0.1524)
			(thermal_gap 0.1524)
		)
		(pad "7" thru_hole circle
			(at 2.500122 2.500122)
			(size 0.762 0.762)
			(drill 0.5588)
			(layers "*.Cu" "*.Mask")
			(remove_unused_layers no)
			(net "GND")
			(clearance 0.1524)
			(thermal_gap 0.1524)
		)
		(pad "8" thru_hole circle
			(at 3.50012 0)
			(size 0.762 0.762)
			(drill 0.5588)
			(layers "*.Cu" "*.Mask")
			(remove_unused_layers no)
			(net "GND")
			(clearance 0.1524)
			(thermal_gap 0.1524)
		)
		(pad "9" thru_hole circle
			(at 2.500122 -2.500122)
			(size 0.762 0.762)
			(drill 0.5588)
			(layers "*.Cu" "*.Mask")
			(remove_unused_layers no)
			(net "GND")
			(clearance 0.1524)
			(thermal_gap 0.1524)
		)
		(zone
			(layer "F.Cu")
			(hatch none 0.5)
			(connect_pads
				(clearance 0)
			)
			(min_thickness 0.25)
			(keepout
				(tracks not_allowed)
				(vias allowed)
				(pads allowed)
				(copperpour not_allowed)
				(footprints allowed)
			)
			(placement
				(enabled no)
				(sheetname "")
			)
			(fill
				(thermal_gap 0.5)
				(thermal_bridge_width 0.5)
				(island_removal_mode 0)
			)
			(polygon
				(pts
					(arc
						(start 77.999844 -438.151016)
						(mid 69.998844 -430.150016)
						(end 77.999844 -422.149016)
					)
					(arc
						(start 77.999844 -422.149016)
						(mid 79.434944 -423.584116)
						(end 77.999844 -425.019216)
					)
					(arc
						(start 77.999844 -425.019216)
						(mid 72.869044 -430.150016)
						(end 77.999844 -435.280816)
					)
					(arc
						(start 77.999844 -435.280816)
						(mid 79.434944 -436.715916)
						(end 77.999844 -438.151016)
					)
				)
			)
		)
		(zone
			(layer "F.Cu")
			(hatch none 0.5)
			(connect_pads
				(clearance 0)
			)
			(min_thickness 0.25)
			(keepout
				(tracks not_allowed)
				(vias allowed)
				(pads allowed)
				(copperpour not_allowed)
				(footprints allowed)
			)
			(placement
				(enabled no)
				(sheetname "")
			)
			(fill
				(thermal_gap 0.5)
				(thermal_bridge_width 0.5)
				(island_removal_mode 0)
			)
			(polygon
				(pts
					(arc
						(start 77.999844 -438.151016)
						(mid 86.000844 -430.150016)
						(end 77.999844 -422.149016)
					)
					(arc
						(start 77.999844 -422.149016)
						(mid 76.564744 -423.584116)
						(end 77.999844 -425.019216)
					)
					(arc
						(start 77.999844 -425.019216)
						(mid 83.130644 -430.150016)
						(end 77.999844 -435.280816)
					)
					(arc
						(start 77.999844 -435.280816)
						(mid 76.564744 -436.715916)
						(end 77.999844 -438.151016)
					)
				)
			)
		)
		(zone
			(layers "F.Cu" "B.Cu" "In1.Cu" "In2.Cu" "In3.Cu" "In4.Cu" "In5.Cu" "In6.Cu")
			(hatch none 0.5)
			(connect_pads
				(clearance 0)
			)
			(min_thickness 0.25)
			(keepout
				(tracks not_allowed)
				(vias allowed)
				(pads allowed)
				(copperpour not_allowed)
				(footprints allowed)
			)
			(placement
				(enabled no)
				(sheetname "")
			)
			(fill
				(thermal_gap 0.5)
				(thermal_bridge_width 0.5)
				(island_removal_mode 0)
			)
			(polygon
				(pts
					(arc
						(start 80.511904 -430.150016)
						(mid 75.487784 -430.150016)
						(end 80.511904 -430.150016)
					)
				)
			)
		)
	)
)
